# BASEBOARD_FAB2 (Tioga Pass) — schematic netlist excerpt (pin names and nets, part order shuffled) for the footprints in the layout excerpt that follows; sources: Cadence DE-HDL packaged netlist, KiCad conversion of Wiwynn_Tioga_Pass_MB.brd

U25W5  H5AN4G6NAFR-TFC-GP  pkg MEMORY-G2  page 151
  VDDQ(0)  = P1V2_AUX_BMC
  VSSQ(0)  = GND
  DQU0  = BMC_M_DQ8
  DQSU_C  = BMC_M_DQS1_DN
  VSSQ(1)  = GND
  VDDQ(1)  = P1V2_AUX_BMC
  VPP(0)  = P2V5_AUX_BMC
  VSS(0)  = GND
  VDD(0)  = P1V2_AUX_BMC
  DQSU_T  = BMC_M_DQS1_DP
  DQU1  = BMC_M_DQ9
  VDD(1)  = P1V2_AUX_BMC
  VDDQ(2)  = P1V2_AUX_BMC
  DQU4  = BMC_M_DQ12
  DQU2  = BMC_M_DQ10
  DQU3  = BMC_M_DQ11
  DQU5  = BMC_M_DQ13
  VSSQ(2)  = GND
  VDD(2)  = P1V2_AUX_BMC
  VSSQ(3)  = GND
  DQU6  = BMC_M_DQ14
  DQU7  = BMC_M_DQ15
  VSSQ(4)  = GND
  VDDQ(3)  = P1V2_AUX_BMC
  VSS(1)  = GND
  \dmu#/dbiu#\  = BMC_M_DM1
  VSSQ(5)  = GND
  \dml#/dbil#\  = BMC_M_DM0
  VSSQ(6)  = GND
  VSS(2)  = GND
  VSSQ(7)  = GND
  VDDQ(4)  = P1V2_AUX_BMC
  DQSL_C  = BMC_M_DQS0_DN
  DQL1  = BMC_M_DQ1
  VDDQ(5)  = P1V2_AUX_BMC
  ZQ  = BMC_ZQ
  VDDQ(6)  = P1V2_AUX_BMC
  DQL0  = BMC_M_DQ0
  DQSL_T  = BMC_M_DQS0_DP
  VDD(3)  = P1V2_AUX_BMC
  VSS(3)  = GND
  VDDQ(7)  = P1V2_AUX_BMC
  VSSQ(8)  = GND
  DQL4  = BMC_M_DQ4
  DQL2  = BMC_M_DQ2
  DQL3  = BMC_M_DQ3
  DQL5  = BMC_M_DQ5
  VSSQ(9)  = GND
  VDD(4)  = P1V2_AUX_BMC
  VDDQ(8)  = P1V2_AUX_BMC
  DQL6  = BMC_M_DQ6
  DQL7  = BMC_M_DQ7
  VDDQ(9)  = P1V2_AUX_BMC
  VDD(5)  = P1V2_AUX_BMC
  VSS(4)  = GND
  CKE  = BMC_M_CKE
  ODT  = BMC_M_ODT
  CK_T  = BMC_M_CLK_DP
  CK_C  = BMC_M_CLK_DN
  VSS(5)  = GND
  VDD(6)  = P1V2_AUX_BMC
  \we#/a14\  = BMC_M_WE_N
  \act#\  = BMC_M_MACT_N
  \cs#\  = BMC_M_CS_N
  \ras#/a16\  = BMC_M_RAS_N
  VDD(7)  = P1V2_AUX_BMC
  VREFCA  = BMC_M_VREFCA
  BG0  = BMC_M_BG0
  \a10/ap\  = BMC_M_A10
  \a12/bc#\  = BMC_M_A12
  \cas#/a15\  = BMC_M_CAS_N
  VSS(6)  = GND
  VSS(7)  = GND
  BA0  = BMC_M_BA0
  A4  = BMC_M_A4
  A3  = BMC_M_A3
  BA1  = BMC_M_BA1
  TEN  = GND
  \reset#\  = BMC_M_RST_N
  A6  = BMC_M_A6
  A0  = BMC_M_A0
  A1  = BMC_M_A1
  A5  = BMC_M_A5
  \alert#\  = BMC_M_MALERT_N
  VDD(8)  = P1V2_AUX_BMC
  A8  = BMC_M_A8
  A2  = BMC_M_A2
  A9  = BMC_M_A9
  A7  = BMC_M_A7
  VPP(1)  = P2V5_AUX_BMC
  VSS(8)  = GND
  A11  = BMC_M_A11
  PAR  = BMC_M_PAR
  \nc#t7\  = NC
  A13  = BMC_M_A13
  VDD(9)  = P1V2_AUX_BMC

(kicad_pcb
	(version 20260206)
	(generator "pcbnew")
	(generator_version "10.0")
	(general
		(thickness 1.6)
		(legacy_teardrops no)
	)
	(paper "A4")
	(title_block
		(title "Wiwynn_Tioga_Pass_MB.brd")
		(comment 1 "Tioga Pass / footprint 1895 of 4770 (U25W5), pads 1-46 of 96")
	)
	(layers
		(0 "F.Cu" signal "TOP")
		(4 "In1.Cu" signal "L2GND")
		(6 "In2.Cu" signal "L3")
		(8 "In3.Cu" signal "L4GND")
		(10 "In4.Cu" signal "L5")
		(12 "In5.Cu" signal "L6GND")
		(14 "In6.Cu" signal "L7VCC")
		(16 "In7.Cu" signal "L8VCC")
		(18 "In8.Cu" signal "L9GND")
		(20 "In9.Cu" signal "L10")
		(22 "In10.Cu" signal "L11GND")
		(24 "In11.Cu" signal "L12")
		(26 "In12.Cu" signal "L13GND")
		(2 "B.Cu" signal "BOTTOM")
		(9 "F.Adhes" user "F.Adhesive")
		(11 "B.Adhes" user "B.Adhesive")
		(13 "F.Paste" user "Package Geometry/Pastemask Top")
		(15 "B.Paste" user "Package Geometry/Pastemask Bottom")
		(5 "F.SilkS" user "Ref Des/Silkscreen Top")
		(7 "B.SilkS" user "Ref Des/Silkscreen Bottom")
		(1 "F.Mask" user "Board Geometry/Soldermask Top")
		(3 "B.Mask" user "Board Geometry/Soldermask Bottom")
		(17 "Dwgs.User" user "User.Drawings")
		(19 "Cmts.User" user "User.Comments")
		(21 "Eco1.User" user "User.Eco1")
		(23 "Eco2.User" user "User.Eco2")
		(25 "Edge.Cuts" user "Board Geometry/Outline")
		(27 "Margin" user)
		(31 "F.CrtYd" user "Package Geometry/Place Bound Top")
		(29 "B.CrtYd" user "Package Geometry/Place Bound Bottom")
		(35 "F.Fab" user "Ref Des/Assembly Top")
		(33 "B.Fab" user "Ref Des/Assembly Bottom")
	)
	(footprint ""
		(layer "F.Cu")
		(at 439.722006 -31.4325 180)
		(property "Reference" "U25W5"
			(at 0 0 180)
			(layer "F.SilkS")
			(hide yes)
			(effects
				(font
					(size 1.27 1.27)
				)
			)
		)
		(property "Value" "*"
			(at -8.423656 -16.0909 180)
			(unlocked yes)
			(layer "F.Fab")
			(hide yes)
			(effects
				(font
					(size 1.27 1.016)
					(thickness 0.1524)
				)
			)
		)
		(property "Device Type" "H5AN4G6NAFR-TFC-GP_MEMORY-G2-HA"
			(at -8.423656 -17.6149 180)
			(unlocked yes)
			(layer "F.Fab")
			(hide yes)
			(effects
				(font
					(size 1.27 1.016)
					(thickness 0.1524)
				)
			)
		)
		(duplicate_pad_numbers_are_jumpers no)
		(pad "A1" smd circle
			(at -3.199892 -5.999988 180)
			(size 0.3556 0.3556)
			(layers "F.Cu" "F.Mask" "F.Paste")
			(net "P1V2_AUX_BMC")
		)
		(pad "A2" smd circle
			(at -2.400046 -5.999988 180)
			(size 0.3556 0.3556)
			(layers "F.Cu" "F.Mask" "F.Paste")
			(net "GND")
		)
		(pad "A3" smd circle
			(at -1.599946 -5.999988 180)
			(size 0.3556 0.3556)
			(layers "F.Cu" "F.Mask" "F.Paste")
			(net "BMC_M_DQ8")
		)
		(pad "A7" smd circle
			(at 1.599946 -5.999988 180)
			(size 0.3556 0.3556)
			(layers "F.Cu" "F.Mask" "F.Paste")
			(net "BMC_M_DQS1_DN")
		)
		(pad "A8" smd circle
			(at 2.400046 -5.999988 180)
			(size 0.3556 0.3556)
			(layers "F.Cu" "F.Mask" "F.Paste")
			(net "GND")
		)
		(pad "A9" smd circle
			(at 3.199892 -5.999988 180)
			(size 0.3556 0.3556)
			(layers "F.Cu" "F.Mask" "F.Paste")
			(net "P1V2_AUX_BMC")
		)
		(pad "B1" smd circle
			(at -3.199892 -5.199888 180)
			(size 0.3556 0.3556)
			(layers "F.Cu" "F.Mask" "F.Paste")
			(net "P2V5_AUX_BMC")
		)
		(pad "B2" smd circle
			(at -2.400046 -5.199888 180)
			(size 0.3556 0.3556)
			(layers "F.Cu" "F.Mask" "F.Paste")
			(net "GND")
		)
		(pad "B3" smd circle
			(at -1.599946 -5.199888 180)
			(size 0.3556 0.3556)
			(layers "F.Cu" "F.Mask" "F.Paste")
			(net "P1V2_AUX_BMC")
		)
		(pad "B7" smd circle
			(at 1.599946 -5.199888 180)
			(size 0.3556 0.3556)
			(layers "F.Cu" "F.Mask" "F.Paste")
			(net "BMC_M_DQS1_DP")
		)
		(pad "B8" smd circle
			(at 2.400046 -5.199888 180)
			(size 0.3556 0.3556)
			(layers "F.Cu" "F.Mask" "F.Paste")
			(net "BMC_M_DQ9")
		)
		(pad "B9" smd circle
			(at 3.199892 -5.199888 180)
			(size 0.3556 0.3556)
			(layers "F.Cu" "F.Mask" "F.Paste")
			(net "P1V2_AUX_BMC")
		)
		(pad "C1" smd circle
			(at -3.199892 -4.400042 180)
			(size 0.3556 0.3556)
			(layers "F.Cu" "F.Mask" "F.Paste")
			(net "P1V2_AUX_BMC")
		)
		(pad "C2" smd circle
			(at -2.400046 -4.400042 180)
			(size 0.3556 0.3556)
			(layers "F.Cu" "F.Mask" "F.Paste")
			(net "BMC_M_DQ12")
		)
		(pad "C3" smd circle
			(at -1.599946 -4.400042 180)
			(size 0.3556 0.3556)
			(layers "F.Cu" "F.Mask" "F.Paste")
			(net "BMC_M_DQ10")
		)
		(pad "C7" smd circle
			(at 1.599946 -4.400042 180)
			(size 0.3556 0.3556)
			(layers "F.Cu" "F.Mask" "F.Paste")
			(net "BMC_M_DQ11")
		)
		(pad "C8" smd circle
			(at 2.400046 -4.400042 180)
			(size 0.3556 0.3556)
			(layers "F.Cu" "F.Mask" "F.Paste")
			(net "BMC_M_DQ13")
		)
		(pad "C9" smd circle
			(at 3.199892 -4.400042 180)
			(size 0.3556 0.3556)
			(layers "F.Cu" "F.Mask" "F.Paste")
			(net "GND")
		)
		(pad "D1" smd circle
			(at -3.199892 -3.599942 180)
			(size 0.3556 0.3556)
			(layers "F.Cu" "F.Mask" "F.Paste")
			(net "P1V2_AUX_BMC")
		)
		(pad "D2" smd circle
			(at -2.400046 -3.599942 180)
			(size 0.3556 0.3556)
			(layers "F.Cu" "F.Mask" "F.Paste")
			(net "GND")
		)
		(pad "D3" smd circle
			(at -1.599946 -3.599942 180)
			(size 0.3556 0.3556)
			(layers "F.Cu" "F.Mask" "F.Paste")
			(net "BMC_M_DQ14")
		)
		(pad "D7" smd circle
			(at 1.599946 -3.599942 180)
			(size 0.3556 0.3556)
			(layers "F.Cu" "F.Mask" "F.Paste")
			(net "BMC_M_DQ15")
		)
		(pad "D8" smd circle
			(at 2.400046 -3.599942 180)
			(size 0.3556 0.3556)
			(layers "F.Cu" "F.Mask" "F.Paste")
			(net "GND")
		)
		(pad "D9" smd circle
			(at 3.199892 -3.599942 180)
			(size 0.3556 0.3556)
			(layers "F.Cu" "F.Mask" "F.Paste")
			(net "P1V2_AUX_BMC")
		)
		(pad "E1" smd circle
			(at -3.199892 -2.800096 180)
			(size 0.3556 0.3556)
			(layers "F.Cu" "F.Mask" "F.Paste")
			(net "GND")
		)
		(pad "E2" smd circle
			(at -2.400046 -2.800096 180)
			(size 0.3556 0.3556)
			(layers "F.Cu" "F.Mask" "F.Paste")
			(net "BMC_M_DM1")
		)
		(pad "E3" smd circle
			(at -1.599946 -2.800096 180)
			(size 0.3556 0.3556)
			(layers "F.Cu" "F.Mask" "F.Paste")
			(net "GND")
		)
		(pad "E7" smd circle
			(at 1.599946 -2.800096 180)
			(size 0.3556 0.3556)
			(layers "F.Cu" "F.Mask" "F.Paste")
			(net "BMC_M_DM0")
		)
		(pad "E8" smd circle
			(at 2.400046 -2.800096 180)
			(size 0.3556 0.3556)
			(layers "F.Cu" "F.Mask" "F.Paste")
			(net "GND")
		)
		(pad "E9" smd circle
			(at 3.199892 -2.800096 180)
			(size 0.3556 0.3556)
			(layers "F.Cu" "F.Mask" "F.Paste")
			(net "GND")
		)
		(pad "F1" smd circle
			(at -3.199892 -1.999996 180)
			(size 0.3556 0.3556)
			(layers "F.Cu" "F.Mask" "F.Paste")
			(net "GND")
		)
		(pad "F2" smd circle
			(at -2.400046 -1.999996 180)
			(size 0.3556 0.3556)
			(layers "F.Cu" "F.Mask" "F.Paste")
			(net "P1V2_AUX_BMC")
		)
		(pad "F3" smd circle
			(at -1.599946 -1.999996 180)
			(size 0.3556 0.3556)
			(layers "F.Cu" "F.Mask" "F.Paste")
			(net "BMC_M_DQS0_DN")
		)
		(pad "F7" smd circle
			(at 1.599946 -1.999996 180)
			(size 0.3556 0.3556)
			(layers "F.Cu" "F.Mask" "F.Paste")
			(net "BMC_M_DQ1")
		)
		(pad "F8" smd circle
			(at 2.400046 -1.999996 180)
			(size 0.3556 0.3556)
			(layers "F.Cu" "F.Mask" "F.Paste")
			(net "P1V2_AUX_BMC")
		)
		(pad "F9" smd circle
			(at 3.199892 -1.999996 180)
			(size 0.3556 0.3556)
			(layers "F.Cu" "F.Mask" "F.Paste")
			(net "BMC_ZQ")
		)
		(pad "G1" smd circle
			(at -3.199892 -1.199896 180)
			(size 0.3556 0.3556)
			(layers "F.Cu" "F.Mask" "F.Paste")
			(net "P1V2_AUX_BMC")
		)
		(pad "G2" smd circle
			(at -2.400046 -1.199896 180)
			(size 0.3556 0.3556)
			(layers "F.Cu" "F.Mask" "F.Paste")
			(net "BMC_M_DQ0")
		)
		(pad "G3" smd circle
			(at -1.599946 -1.199896 180)
			(size 0.3556 0.3556)
			(layers "F.Cu" "F.Mask" "F.Paste")
			(net "BMC_M_DQS0_DP")
		)
		(pad "G7" smd circle
			(at 1.599946 -1.199896 180)
			(size 0.3556 0.3556)
			(layers "F.Cu" "F.Mask" "F.Paste")
			(net "P1V2_AUX_BMC")
		)
		(pad "G8" smd circle
			(at 2.400046 -1.199896 180)
			(size 0.3556 0.3556)
			(layers "F.Cu" "F.Mask" "F.Paste")
			(net "GND")
		)
		(pad "G9" smd circle
			(at 3.199892 -1.199896 180)
			(size 0.3556 0.3556)
			(layers "F.Cu" "F.Mask" "F.Paste")
			(net "P1V2_AUX_BMC")
		)
		(pad "H1" smd circle
			(at -3.199892 -0.40005 180)
			(size 0.3556 0.3556)
			(layers "F.Cu" "F.Mask" "F.Paste")
			(net "GND")
		)
		(pad "H2" smd circle
			(at -2.400046 -0.40005 180)
			(size 0.3556 0.3556)
			(layers "F.Cu" "F.Mask" "F.Paste")
			(net "BMC_M_DQ4")
		)
		(pad "H3" smd circle
			(at -1.599946 -0.40005 180)
			(size 0.3556 0.3556)
			(layers "F.Cu" "F.Mask" "F.Paste")
			(net "BMC_M_DQ2")
		)
		(pad "H7" smd circle
			(at 1.599946 -0.40005 180)
			(size 0.3556 0.3556)
			(layers "F.Cu" "F.Mask" "F.Paste")
			(net "BMC_M_DQ3")
		)
	)
)
